(kicad_pcb
	(version 20260206)
	(generator "pcbnew")
	(generator_version "10.0")
	(general
		(thickness 1.6)
		(legacy_teardrops no)
	)
	(paper "A4")
	(title_block
		(title "04192023_DAF0TMB3IC0_F0TG_MB_C_brd_V02_OCP.brd")
		(comment 1 "Grand Teton / footprints 6376-6382 of 8354")
	)
	(layers
		(0 "F.Cu" signal "TOP")
		(4 "In1.Cu" signal "GND")
		(6 "In2.Cu" signal "IN1")
		(8 "In3.Cu" signal "GND1")
		(10 "In4.Cu" signal "IN2")
		(12 "In5.Cu" signal "GND2")
		(14 "In6.Cu" signal "IN3")
		(16 "In7.Cu" signal "GND3")
		(18 "In8.Cu" signal "VCC")
		(20 "In9.Cu" signal "VCC1")
		(22 "In10.Cu" signal "GND4")
		(24 "In11.Cu" signal "IN4")
		(26 "In12.Cu" signal "GND5")
		(28 "In13.Cu" signal "IN5")
		(30 "In14.Cu" signal "GND6")
		(32 "In15.Cu" signal "IN6")
		(34 "In16.Cu" signal "GND7")
		(2 "B.Cu" signal "BOTTOM")
		(9 "F.Adhes" user "F.Adhesive")
		(11 "B.Adhes" user "B.Adhesive")
		(13 "F.Paste" user "Package Geometry/Pastemask Top")
		(15 "B.Paste" user "Package Geometry/Pastemask Bottom")
		(5 "F.SilkS" user "Ref Des/Silkscreen Top")
		(7 "B.SilkS" user "Ref Des/Silkscreen Bottom")
		(1 "F.Mask" user "Board Geometry/Soldermask Top")
		(3 "B.Mask" user "Board Geometry/Soldermask Bottom")
		(17 "Dwgs.User" user "User.Drawings")
		(19 "Cmts.User" user "User.Comments")
		(21 "Eco1.User" user "User.Eco1")
		(23 "Eco2.User" user "User.Eco2")
		(25 "Edge.Cuts" user "Board Geometry/Outline")
		(27 "Margin" user)
		(31 "F.CrtYd" user "Package Geometry/Place Bound Top")
		(29 "B.CrtYd" user "Package Geometry/Place Bound Bottom")
		(35 "F.Fab" user "Ref Des/Assembly Top")
		(33 "B.Fab" user "Ref Des/Assembly Bottom")
	)
	(footprint ""
		(layer "B.Cu")
		(at 138.341354 -164.957252 90)
		(property "Reference" "PR339"
			(at 0 0 90)
			(layer "B.SilkS")
			(hide yes)
			(effects
				(font
					(size 1.27 1.27)
				)
				(justify mirror)
			)
		)
		(property "Value" ""
			(at 0 0 90)
			(layer "B.Fab")
			(effects
				(font
					(size 1.27 1.27)
				)
				(justify mirror)
			)
		)
		(duplicate_pad_numbers_are_jumpers no)
		(fp_line
			(start 0.7874 -0.4064)
			(end -0.7874 -0.4064)
			(stroke
				(width 0.1524)
				(type default)
			)
			(layer "B.SilkS")
		)
		(fp_line
			(start -0.7874 -0.4064)
			(end -0.7874 0.4064)
			(stroke
				(width 0.1524)
				(type default)
			)
			(layer "B.SilkS")
		)
		(fp_line
			(start 0.7874 0.4064)
			(end 0.7874 -0.4064)
			(stroke
				(width 0.1524)
				(type default)
			)
			(layer "B.SilkS")
		)
		(fp_line
			(start -0.7874 0.4064)
			(end 0.7874 0.4064)
			(stroke
				(width 0.1524)
				(type default)
			)
			(layer "B.SilkS")
		)
		(fp_line
			(start 0.67945 -0.305054)
			(end 0.12065 -0.305054)
			(stroke
				(width 0.1)
				(type default)
			)
			(layer "B.Fab")
		)
		(fp_line
			(start 0.12065 -0.305054)
			(end 0.12065 -0.2794)
			(stroke
				(width 0.1)
				(type default)
			)
			(layer "B.Fab")
		)
		(fp_line
			(start -0.12065 -0.3048)
			(end -0.67945 -0.3048)
			(stroke
				(width 0.1)
				(type default)
			)
			(layer "B.Fab")
		)
		(fp_line
			(start -0.67945 -0.3048)
			(end -0.67945 0.3048)
			(stroke
				(width 0.1)
				(type default)
			)
			(layer "B.Fab")
		)
		(fp_line
			(start 0.12065 -0.2794)
			(end -0.12065 -0.2794)
			(stroke
				(width 0.1)
				(type default)
			)
			(layer "B.Fab")
		)
		(fp_line
			(start -0.12065 -0.2794)
			(end -0.12065 -0.3048)
			(stroke
				(width 0.1)
				(type default)
			)
			(layer "B.Fab")
		)
		(fp_line
			(start 0.12065 0.2794)
			(end 0.12065 0.3048)
			(stroke
				(width 0.1)
				(type default)
			)
			(layer "B.Fab")
		)
		(fp_line
			(start -0.120396 0.2794)
			(end 0.12065 0.2794)
			(stroke
				(width 0.1)
				(type default)
			)
			(layer "B.Fab")
		)
		(fp_line
			(start 0.67945 0.3048)
			(end 0.67945 -0.305054)
			(stroke
				(width 0.1)
				(type default)
			)
			(layer "B.Fab")
		)
		(fp_line
			(start 0.12065 0.3048)
			(end 0.67945 0.3048)
			(stroke
				(width 0.1)
				(type default)
			)
			(layer "B.Fab")
		)
		(fp_line
			(start -0.120396 0.3048)
			(end -0.120396 0.2794)
			(stroke
				(width 0.1)
				(type default)
			)
			(layer "B.Fab")
		)
		(fp_line
			(start -0.67945 0.3048)
			(end -0.120396 0.3048)
			(stroke
				(width 0.1)
				(type default)
			)
			(layer "B.Fab")
		)
		(pad "1" smd circle
			(at 0.40005 0 270)
			(size 0 0)
			(layers "B.Cu" "B.Mask" "B.Paste")
			(net "PVDDCR_SOC_P1")
		)
		(pad "2" smd circle
			(at -0.40005 0 270)
			(size 0 0)
			(layers "B.Cu" "B.Mask" "B.Paste")
			(net "GND")
		)
	)
	(footprint ""
		(layer "B.Cu")
		(at 434.39842 -438.1119 90)
		(property "Reference" "R4166"
			(at 0 0 90)
			(layer "B.SilkS")
			(hide yes)
			(effects
				(font
					(size 1.27 1.27)
				)
				(justify mirror)
			)
		)
		(property "Value" ""
			(at 0 0 90)
			(layer "B.Fab")
			(effects
				(font
					(size 1.27 1.27)
				)
				(justify mirror)
			)
		)
		(duplicate_pad_numbers_are_jumpers no)
		(fp_line
			(start 0.7874 -0.4064)
			(end -0.7874 -0.4064)
			(stroke
				(width 0.1524)
				(type default)
			)
			(layer "B.SilkS")
		)
		(fp_line
			(start -0.7874 -0.4064)
			(end -0.7874 0.4064)
			(stroke
				(width 0.1524)
				(type default)
			)
			(layer "B.SilkS")
		)
		(fp_line
			(start 0.7874 0.4064)
			(end 0.7874 -0.4064)
			(stroke
				(width 0.1524)
				(type default)
			)
			(layer "B.SilkS")
		)
		(fp_line
			(start -0.7874 0.4064)
			(end 0.7874 0.4064)
			(stroke
				(width 0.1524)
				(type default)
			)
			(layer "B.SilkS")
		)
		(fp_line
			(start 0.67945 -0.305054)
			(end 0.12065 -0.305054)
			(stroke
				(width 0.1)
				(type default)
			)
			(layer "B.Fab")
		)
		(fp_line
			(start 0.12065 -0.305054)
			(end 0.12065 -0.2794)
			(stroke
				(width 0.1)
				(type default)
			)
			(layer "B.Fab")
		)
		(fp_line
			(start -0.12065 -0.3048)
			(end -0.67945 -0.3048)
			(stroke
				(width 0.1)
				(type default)
			)
			(layer "B.Fab")
		)
		(fp_line
			(start -0.67945 -0.3048)
			(end -0.67945 0.3048)
			(stroke
				(width 0.1)
				(type default)
			)
			(layer "B.Fab")
		)
		(fp_line
			(start 0.12065 -0.2794)
			(end -0.12065 -0.2794)
			(stroke
				(width 0.1)
				(type default)
			)
			(layer "B.Fab")
		)
		(fp_line
			(start -0.12065 -0.2794)
			(end -0.12065 -0.3048)
			(stroke
				(width 0.1)
				(type default)
			)
			(layer "B.Fab")
		)
		(fp_line
			(start 0.12065 0.2794)
			(end 0.12065 0.3048)
			(stroke
				(width 0.1)
				(type default)
			)
			(layer "B.Fab")
		)
		(fp_line
			(start -0.120396 0.2794)
			(end 0.12065 0.2794)
			(stroke
				(width 0.1)
				(type default)
			)
			(layer "B.Fab")
		)
		(fp_line
			(start 0.67945 0.3048)
			(end 0.67945 -0.305054)
			(stroke
				(width 0.1)
				(type default)
			)
			(layer "B.Fab")
		)
		(fp_line
			(start 0.12065 0.3048)
			(end 0.67945 0.3048)
			(stroke
				(width 0.1)
				(type default)
			)
			(layer "B.Fab")
		)
		(fp_line
			(start -0.120396 0.3048)
			(end -0.120396 0.2794)
			(stroke
				(width 0.1)
				(type default)
			)
			(layer "B.Fab")
		)
		(fp_line
			(start -0.67945 0.3048)
			(end -0.120396 0.3048)
			(stroke
				(width 0.1)
				(type default)
			)
			(layer "B.Fab")
		)
		(pad "1" smd circle
			(at 0.40005 0 270)
			(size 0 0)
			(layers "B.Cu" "B.Mask" "B.Paste")
			(net "P3V3_AUX")
		)
		(pad "2" smd circle
			(at -0.40005 0 270)
			(size 0 0)
			(layers "B.Cu" "B.Mask" "B.Paste")
			(net "GPU_3V3IO_RSVD3_N")
		)
	)
	(footprint ""
		(layer "B.Cu")
		(at 131.59105 -213.203028 90)
		(property "Reference" "R529"
			(at 0 0 90)
			(layer "B.SilkS")
			(hide yes)
			(effects
				(font
					(size 1.27 1.27)
				)
				(justify mirror)
			)
		)
		(property "Value" ""
			(at 0 0 90)
			(layer "B.Fab")
			(effects
				(font
					(size 1.27 1.27)
				)
				(justify mirror)
			)
		)
		(duplicate_pad_numbers_are_jumpers no)
		(fp_line
			(start 0.7874 -0.4064)
			(end -0.7874 -0.4064)
			(stroke
				(width 0.1524)
				(type default)
			)
			(layer "B.SilkS")
		)
		(fp_line
			(start -0.7874 -0.4064)
			(end -0.7874 0.4064)
			(stroke
				(width 0.1524)
				(type default)
			)
			(layer "B.SilkS")
		)
		(fp_line
			(start 0.7874 0.4064)
			(end 0.7874 -0.4064)
			(stroke
				(width 0.1524)
				(type default)
			)
			(layer "B.SilkS")
		)
		(fp_line
			(start -0.7874 0.4064)
			(end 0.7874 0.4064)
			(stroke
				(width 0.1524)
				(type default)
			)
			(layer "B.SilkS")
		)
		(fp_line
			(start 0.67945 -0.305054)
			(end 0.12065 -0.305054)
			(stroke
				(width 0.1)
				(type default)
			)
			(layer "B.Fab")
		)
		(fp_line
			(start 0.12065 -0.305054)
			(end 0.12065 -0.2794)
			(stroke
				(width 0.1)
				(type default)
			)
			(layer "B.Fab")
		)
		(fp_line
			(start -0.12065 -0.3048)
			(end -0.67945 -0.3048)
			(stroke
				(width 0.1)
				(type default)
			)
			(layer "B.Fab")
		)
		(fp_line
			(start -0.67945 -0.3048)
			(end -0.67945 0.3048)
			(stroke
				(width 0.1)
				(type default)
			)
			(layer "B.Fab")
		)
		(fp_line
			(start 0.12065 -0.2794)
			(end -0.12065 -0.2794)
			(stroke
				(width 0.1)
				(type default)
			)
			(layer "B.Fab")
		)
		(fp_line
			(start -0.12065 -0.2794)
			(end -0.12065 -0.3048)
			(stroke
				(width 0.1)
				(type default)
			)
			(layer "B.Fab")
		)
		(fp_line
			(start 0.12065 0.2794)
			(end 0.12065 0.3048)
			(stroke
				(width 0.1)
				(type default)
			)
			(layer "B.Fab")
		)
		(fp_line
			(start -0.120396 0.2794)
			(end 0.12065 0.2794)
			(stroke
				(width 0.1)
				(type default)
			)
			(layer "B.Fab")
		)
		(fp_line
			(start 0.67945 0.3048)
			(end 0.67945 -0.305054)
			(stroke
				(width 0.1)
				(type default)
			)
			(layer "B.Fab")
		)
		(fp_line
			(start 0.12065 0.3048)
			(end 0.67945 0.3048)
			(stroke
				(width 0.1)
				(type default)
			)
			(layer "B.Fab")
		)
		(fp_line
			(start -0.120396 0.3048)
			(end -0.120396 0.2794)
			(stroke
				(width 0.1)
				(type default)
			)
			(layer "B.Fab")
		)
		(fp_line
			(start -0.67945 0.3048)
			(end -0.120396 0.3048)
			(stroke
				(width 0.1)
				(type default)
			)
			(layer "B.Fab")
		)
		(pad "1" smd circle
			(at 0.40005 0 270)
			(size 0 0)
			(layers "B.Cu" "B.Mask" "B.Paste")
			(net "JTAG_CPU1_R_TDO")
		)
		(pad "2" smd circle
			(at -0.40005 0 270)
			(size 0 0)
			(layers "B.Cu" "B.Mask" "B.Paste")
			(net "JTAG_CPU1_TDO")
		)
	)
	(footprint ""
		(layer "B.Cu")
		(at 43.265852 -382.68656 180)
		(property "Reference" "R6722"
			(at 0 0 0)
			(layer "B.SilkS")
			(hide yes)
			(effects
				(font
					(size 1.27 1.27)
				)
				(justify mirror)
			)
		)
		(property "Value" ""
			(at 0 0 0)
			(layer "B.Fab")
			(effects
				(font
					(size 1.27 1.27)
				)
				(justify mirror)
			)
		)
		(duplicate_pad_numbers_are_jumpers no)
		(fp_line
			(start 0.32512 0.175006)
			(end 0.32512 -0.175006)
			(stroke
				(width 0.1)
				(type default)
			)
			(layer "B.Fab")
		)
		(fp_line
			(start 0.32512 -0.175006)
			(end -0.32512 -0.175006)
			(stroke
				(width 0.1)
				(type default)
			)
			(layer "B.Fab")
		)
		(fp_line
			(start -0.32512 0.175006)
			(end 0.32512 0.175006)
			(stroke
				(width 0.1)
				(type default)
			)
			(layer "B.Fab")
		)
		(fp_line
			(start -0.32512 -0.175006)
			(end -0.32512 0.175006)
			(stroke
				(width 0.1)
				(type default)
			)
			(layer "B.Fab")
		)
		(pad "1" smd rect
			(at 0.2667 0)
			(size 0.3048 0.381)
			(layers "B.Cu" "B.Mask" "B.Paste")
			(net "P1V8_CPU1_RT_1D")
		)
		(pad "2" smd rect
			(at -0.2667 0 180)
			(size 0.3048 0.381)
			(layers "B.Cu" "B.Mask" "B.Paste")
			(net "RT_CPU1_P0_SCAN_MODE")
		)
	)
	(footprint ""
		(layer "B.Cu")
		(at 157.989778 -17.969992 -90)
		(property "Reference" "R3114"
			(at 0 0 90)
			(layer "B.SilkS")
			(hide yes)
			(effects
				(font
					(size 1.27 1.27)
				)
				(justify mirror)
			)
		)
		(property "Value" ""
			(at 0 0 90)
			(layer "B.Fab")
			(effects
				(font
					(size 1.27 1.27)
				)
				(justify mirror)
			)
		)
		(duplicate_pad_numbers_are_jumpers no)
		(fp_line
			(start -0.7874 0.4064)
			(end 0.7874 0.4064)
			(stroke
				(width 0.1524)
				(type default)
			)
			(layer "B.SilkS")
		)
		(fp_line
			(start 0.7874 0.4064)
			(end 0.7874 -0.4064)
			(stroke
				(width 0.1524)
				(type default)
			)
			(layer "B.SilkS")
		)
		(fp_line
			(start -0.7874 -0.4064)
			(end -0.7874 0.4064)
			(stroke
				(width 0.1524)
				(type default)
			)
			(layer "B.SilkS")
		)
		(fp_line
			(start 0.7874 -0.4064)
			(end -0.7874 -0.4064)
			(stroke
				(width 0.1524)
				(type default)
			)
			(layer "B.SilkS")
		)
		(fp_line
			(start -0.67945 0.3048)
			(end -0.120396 0.3048)
			(stroke
				(width 0.1)
				(type default)
			)
			(layer "B.Fab")
		)
		(fp_line
			(start -0.120396 0.3048)
			(end -0.120396 0.2794)
			(stroke
				(width 0.1)
				(type default)
			)
			(layer "B.Fab")
		)
		(fp_line
			(start 0.12065 0.3048)
			(end 0.67945 0.3048)
			(stroke
				(width 0.1)
				(type default)
			)
			(layer "B.Fab")
		)
		(fp_line
			(start 0.67945 0.3048)
			(end 0.67945 -0.305054)
			(stroke
				(width 0.1)
				(type default)
			)
			(layer "B.Fab")
		)
		(fp_line
			(start -0.120396 0.2794)
			(end 0.12065 0.2794)
			(stroke
				(width 0.1)
				(type default)
			)
			(layer "B.Fab")
		)
		(fp_line
			(start 0.12065 0.2794)
			(end 0.12065 0.3048)
			(stroke
				(width 0.1)
				(type default)
			)
			(layer "B.Fab")
		)
		(fp_line
			(start -0.12065 -0.2794)
			(end -0.12065 -0.3048)
			(stroke
				(width 0.1)
				(type default)
			)
			(layer "B.Fab")
		)
		(fp_line
			(start 0.12065 -0.2794)
			(end -0.12065 -0.2794)
			(stroke
				(width 0.1)
				(type default)
			)
			(layer "B.Fab")
		)
		(fp_line
			(start -0.67945 -0.3048)
			(end -0.67945 0.3048)
			(stroke
				(width 0.1)
				(type default)
			)
			(layer "B.Fab")
		)
		(fp_line
			(start -0.12065 -0.3048)
			(end -0.67945 -0.3048)
			(stroke
				(width 0.1)
				(type default)
			)
			(layer "B.Fab")
		)
		(fp_line
			(start 0.12065 -0.305054)
			(end 0.12065 -0.2794)
			(stroke
				(width 0.1)
				(type default)
			)
			(layer "B.Fab")
		)
		(fp_line
			(start 0.67945 -0.305054)
			(end 0.12065 -0.305054)
			(stroke
				(width 0.1)
				(type default)
			)
			(layer "B.Fab")
		)
		(pad "1" smd circle
			(at 0.40005 0 90)
			(size 0 0)
			(layers "B.Cu" "B.Mask" "B.Paste")
			(net "SMB_FAN_3V3AUX_SDA")
		)
		(pad "2" smd circle
			(at -0.40005 0 90)
			(size 0 0)
			(layers "B.Cu" "B.Mask" "B.Paste")
			(net "SMB_FAN_3V3AUX_R_SDA")
		)
	)
	(footprint ""
		(layer "B.Cu")
		(at 127.691134 -390.560052 90)
		(property "Reference" "C483"
			(at 0 0 90)
			(layer "B.SilkS")
			(hide yes)
			(effects
				(font
					(size 1.27 1.27)
				)
				(justify mirror)
			)
		)
		(property "Value" ""
			(at 0 0 90)
			(layer "B.Fab")
			(effects
				(font
					(size 1.27 1.27)
				)
				(justify mirror)
			)
		)
		(duplicate_pad_numbers_are_jumpers no)
		(fp_line
			(start 0.7874 -0.4064)
			(end -0.7874 -0.4064)
			(stroke
				(width 0.1524)
				(type default)
			)
			(layer "B.SilkS")
		)
		(fp_line
			(start -0.7874 -0.4064)
			(end -0.7874 0.4064)
			(stroke
				(width 0.1524)
				(type default)
			)
			(layer "B.SilkS")
		)
		(fp_line
			(start 0.7874 0.4064)
			(end 0.7874 -0.4064)
			(stroke
				(width 0.1524)
				(type default)
			)
			(layer "B.SilkS")
		)
		(fp_line
			(start -0.7874 0.4064)
			(end 0.7874 0.4064)
			(stroke
				(width 0.1524)
				(type default)
			)
			(layer "B.SilkS")
		)
		(fp_line
			(start 0.67945 -0.305054)
			(end 0.12065 -0.305054)
			(stroke
				(width 0.1)
				(type default)
			)
			(layer "B.Fab")
		)
		(fp_line
			(start 0.12065 -0.305054)
			(end 0.12065 -0.2794)
			(stroke
				(width 0.1)
				(type default)
			)
			(layer "B.Fab")
		)
		(fp_line
			(start -0.12065 -0.3048)
			(end -0.67945 -0.3048)
			(stroke
				(width 0.1)
				(type default)
			)
			(layer "B.Fab")
		)
		(fp_line
			(start -0.67945 -0.3048)
			(end -0.67945 0.3048)
			(stroke
				(width 0.1)
				(type default)
			)
			(layer "B.Fab")
		)
		(fp_line
			(start 0.12065 -0.2794)
			(end -0.12065 -0.2794)
			(stroke
				(width 0.1)
				(type default)
			)
			(layer "B.Fab")
		)
		(fp_line
			(start -0.12065 -0.2794)
			(end -0.12065 -0.3048)
			(stroke
				(width 0.1)
				(type default)
			)
			(layer "B.Fab")
		)
		(fp_line
			(start 0.12065 0.2794)
			(end 0.12065 0.3048)
			(stroke
				(width 0.1)
				(type default)
			)
			(layer "B.Fab")
		)
		(fp_line
			(start -0.120396 0.2794)
			(end 0.12065 0.2794)
			(stroke
				(width 0.1)
				(type default)
			)
			(layer "B.Fab")
		)
		(fp_line
			(start 0.67945 0.3048)
			(end 0.67945 -0.305054)
			(stroke
				(width 0.1)
				(type default)
			)
			(layer "B.Fab")
		)
		(fp_line
			(start 0.12065 0.3048)
			(end 0.67945 0.3048)
			(stroke
				(width 0.1)
				(type default)
			)
			(layer "B.Fab")
		)
		(fp_line
			(start -0.120396 0.3048)
			(end -0.120396 0.2794)
			(stroke
				(width 0.1)
				(type default)
			)
			(layer "B.Fab")
		)
		(fp_line
			(start -0.67945 0.3048)
			(end -0.120396 0.3048)
			(stroke
				(width 0.1)
				(type default)
			)
			(layer "B.Fab")
		)
		(pad "1" smd circle
			(at 0.40005 0 270)
			(size 0 0)
			(layers "B.Cu" "B.Mask" "B.Paste")
			(net "P0V9_CPU1_RT3_2A")
		)
		(pad "2" smd circle
			(at -0.40005 0 270)
			(size 0 0)
			(layers "B.Cu" "B.Mask" "B.Paste")
			(net "GND")
		)
	)
	(footprint ""
		(layer "B.Cu")
		(at 156.151834 -320.798952)
		(property "Reference" "R513"
			(at 0 0 0)
			(layer "B.SilkS")
			(hide yes)
			(effects
				(font
					(size 1.27 1.27)
				)
				(justify mirror)
			)
		)
		(property "Value" ""
			(at 0 0 0)
			(layer "B.Fab")
			(effects
				(font
					(size 1.27 1.27)
				)
				(justify mirror)
			)
		)
		(duplicate_pad_numbers_are_jumpers no)
		(fp_line
			(start -0.7874 -0.4064)
			(end -0.7874 0.4064)
			(stroke
				(width 0.1524)
				(type default)
			)
			(layer "B.SilkS")
		)
		(fp_line
			(start -0.7874 0.4064)
			(end 0.7874 0.4064)
			(stroke
				(width 0.1524)
				(type default)
			)
			(layer "B.SilkS")
		)
		(fp_line
			(start 0.7874 -0.4064)
			(end -0.7874 -0.4064)
			(stroke
				(width 0.1524)
				(type default)
			)
			(layer "B.SilkS")
		)
		(fp_line
			(start 0.7874 0.4064)
			(end 0.7874 -0.4064)
			(stroke
				(width 0.1524)
				(type default)
			)
			(layer "B.SilkS")
		)
		(fp_line
			(start -0.67945 -0.3048)
			(end -0.67945 0.3048)
			(stroke
				(width 0.1)
				(type default)
			)
			(layer "B.Fab")
		)
		(fp_line
			(start -0.67945 0.3048)
			(end -0.120396 0.3048)
			(stroke
				(width 0.1)
				(type default)
			)
			(layer "B.Fab")
		)
		(fp_line
			(start -0.12065 -0.3048)
			(end -0.67945 -0.3048)
			(stroke
				(width 0.1)
				(type default)
			)
			(layer "B.Fab")
		)
		(fp_line
			(start -0.12065 -0.2794)
			(end -0.12065 -0.3048)
			(stroke
				(width 0.1)
				(type default)
			)
			(layer "B.Fab")
		)
		(fp_line
			(start -0.120396 0.2794)
			(end 0.12065 0.2794)
			(stroke
				(width 0.1)
				(type default)
			)
			(layer "B.Fab")
		)
		(fp_line
			(start -0.120396 0.3048)
			(end -0.120396 0.2794)
			(stroke
				(width 0.1)
				(type default)
			)
			(layer "B.Fab")
		)
		(fp_line
			(start 0.12065 -0.305054)
			(end 0.12065 -0.2794)
			(stroke
				(width 0.1)
				(type default)
			)
			(layer "B.Fab")
		)
		(fp_line
			(start 0.12065 -0.2794)
			(end -0.12065 -0.2794)
			(stroke
				(width 0.1)
				(type default)
			)
			(layer "B.Fab")
		)
		(fp_line
			(start 0.12065 0.2794)
			(end 0.12065 0.3048)
			(stroke
				(width 0.1)
				(type default)
			)
			(layer "B.Fab")
		)
		(fp_line
			(start 0.12065 0.3048)
			(end 0.67945 0.3048)
			(stroke
				(width 0.1)
				(type default)
			)
			(layer "B.Fab")
		)
		(fp_line
			(start 0.67945 -0.305054)
			(end 0.12065 -0.305054)
			(stroke
				(width 0.1)
				(type default)
			)
			(layer "B.Fab")
		)
		(fp_line
			(start 0.67945 0.3048)
			(end 0.67945 -0.305054)
			(stroke
				(width 0.1)
				(type default)
			)
			(layer "B.Fab")
		)
		(pad "1" smd circle
			(at 0.40005 0 180)
			(size 0 0)
			(layers "B.Cu" "B.Mask" "B.Paste")
			(net "P3V3_AUX")
		)
		(pad "2" smd circle
			(at -0.40005 0 180)
			(size 0 0)
			(layers "B.Cu" "B.Mask" "B.Paste")
			(net "CPU1_SP5R4")
		)
	)
)
